#ISCELL
  logical_power cad_note *
  *
#ISCELL
  pure_quanta quanta_title_block_c *
  *
#CELL
  pure_quanta q_cap *
  page16_i100
#ISCELL
  logical_power universal_gnd *
  page16_i105
#CELL
  pure_quanta q_cap *
  page16_i106
#ISCELL
  logical_power universal_power *
  page16_i107
#CELL
  pure_quanta q_cap *
  page16_i118
#CELL
  pure_quanta q_cap *
  page16_i119
#CELL
  pure_quanta q_cap *
  page16_i120
#ISCELL
  logical_power universal_gnd *
  page16_i121
#ISCELL
  logical_power universal_power *
  page16_i122
#CELL
  pure_quanta q_cap *
  page16_i123
#CELL
  pure_quanta q_cap *
  page16_i124
#ISCELL
  logical_power universal_power *
  page16_i125
#CELL
  pure_quanta q_cap *
  page16_i126
#CELL
  pure_quanta q_cap *
  page16_i127
#CELL
  pure_quanta q_cap *
  page16_i128
#CELL
  pure_quanta q_cap *
  page16_i129
#CELL
  pure_quanta q_cap *
  page16_i131
#CELL
  pure_quanta q_cap *
  page16_i132
#CELL
  pure_quanta q_cap *
  page16_i133
#ISCELL
  logical_power universal_gnd *
  page16_i134
#CELL
  pure_quanta q_cap *
  page16_i135
#ISCELL
  logical_power universal_gnd *
  page16_i137
#CELL
  pure_quanta q_cap *
  page16_i143
#ISCELL
  logical_power universal_power *
  page16_i144
#ISCELL
  logical_power universal_power *
  page16_i146
#CELL
  pure_quanta q_cap *
  page16_i147
#CELL
  pure_quanta q_cap *
  page16_i148
#CELL
  pure_quanta q_cap *
  page16_i149
#CELL
  pure_quanta q_cap *
  page16_i150
#CELL
  pure_quanta q_cap *
  page16_i151
#CELL
  pure_quanta q_cap *
  page16_i152
#CELL
  pure_quanta q_cap *
  page16_i153
#CELL
  pure_quanta q_cap *
  page16_i154
#CELL
  pure_quanta q_cap *
  page16_i155
#CELL
  pure_quanta q_cap *
  page16_i156
#CELL
  pure_quanta q_cap *
  page16_i157
#CELL
  pure_quanta q_cap *
  page16_i158
#CELL
  pure_quanta q_cap *
  page16_i159
#ISCELL
  logical_power universal_gnd *
  page16_i161
#CELL
  pure_quanta q_cap *
  page16_i162
#CELL
  pure_quanta q_cap *
  page16_i163
#CELL
  pure_quanta q_cap *
  page16_i164
#CELL
  pure_quanta q_cap *
  page16_i165
#CELL
  pure_quanta q_cap *
  page16_i166
#CELL
  pure_quanta q_cap *
  page16_i167
#CELL
  pure_quanta q_cap *
  page16_i168
#CELL
  pure_quanta q_cap *
  page16_i169
#ISCELL
  logical_power universal_power *
  page16_i170
#CELL
  pure_quanta q_cap *
  page16_i171
#ISCELL
  logical_power universal_power *
  page16_i172
#CELL
  pure_quanta q_cap *
  page16_i173
#CELL
  pure_quanta q_cap *
  page16_i174
#ISCELL
  logical_power universal_gnd *
  page16_i175
#ISCELL
  logical_power universal_power *
  page16_i178
#CELL
  pure_quanta q_cap *
  page16_i179
#CELL
  pure_quanta q_cap *
  page16_i180
#ISCELL
  standard offpage *
  page16_i182
#CELL
  pure_quanta q_cap *
  page16_i183
#ISCELL
  logical_power universal_gnd *
  page16_i184
#ISCELL
  standard offpage *
  page16_i185
#ISCELL
  standard offpage *
  page16_i186
#CELL
  pure_quanta q_res *
  page16_i187
#CELL
  pure_quanta ast2600a3gp *
  page16_i188
#CELL
  pure_quanta q_cap *
  page16_i189
#CELL
  pure_quanta q_cap *
  page16_i190
#CELL
  pure_quanta q_cap *
  page16_i191
#CELL
  pure_quanta q_cap *
  page16_i192
#CELL
  pure_quanta q_cap *
  page16_i193
#ISCELL
  logical_power universal_power *
  page16_i21
#ISCELL
  logical_power universal_power *
  page16_i22
#CELL
  pure_quanta q_cap *
  page16_i23
#CELL
  pure_quanta q_inductor *
  page16_i24
#ISCELL
  logical_power universal_power *
  page16_i25
#CELL
  pure_quanta q_inductor *
  page16_i29
#ISCELL
  logical_power universal_power *
  page16_i30
#CELL
  pure_quanta q_cap *
  page16_i31
#CELL
  pure_quanta q_cap *
  page16_i32
#CELL
  pure_quanta q_cap *
  page16_i33
#ISCELL
  logical_power universal_power *
  page16_i44
#CELL
  pure_quanta q_cap *
  page16_i46
#CELL
  pure_quanta q_inductor *
  page16_i47
#CELL
  pure_quanta q_cap *
  page16_i48
#CELL
  pure_quanta q_cap *
  page16_i49
#ISCELL
  logical_power universal_gnd *
  page16_i50
#CELL
  pure_quanta q_cap *
  page16_i51
#CELL
  pure_quanta q_cap *
  page16_i52
#CELL
  pure_quanta q_cap *
  page16_i53
#CELL
  pure_quanta q_cap *
  page16_i54
#CELL
  pure_quanta q_cap *
  page16_i55
#ISCELL
  logical_power universal_gnd *
  page16_i56
#CELL
  pure_quanta q_cap *
  page16_i57
#CELL
  pure_quanta q_cap *
  page16_i58
#CELL
  pure_quanta q_cap *
  page16_i59
#ISCELL
  logical_power universal_power *
  page16_i60
#ISCELL
  logical_power universal_power *
  page16_i61
#ISCELL
  logical_power universal_gnd *
  page16_i62
#ISCELL
  logical_power universal_power *
  page16_i63
#ISCELL
  logical_power universal_power *
  page16_i64
#ISCELL
  logical_power universal_power *
  page16_i65
#CELL
  pure_quanta q_cap *
  page16_i66
#ISCELL
  standard offpage *
  page16_i67
#ISCELL
  standard offpage *
  page16_i68
#ISCELL
  standard offpage *
  page16_i69
#ISCELL
  standard offpage *
  page16_i70
#CELL
  pure_quanta q_cap *
  page16_i79
#ISCELL
  logical_power universal_gnd *
  page16_i80
#CELL
  pure_quanta q_cap *
  page16_i81
#CELL
  pure_quanta q_cap *
  page16_i82
#ISCELL
  logical_power universal_gnd *
  page16_i83
#CELL
  pure_quanta q_res *
  page16_i86
#CELL
  pure_quanta q_res *
  page16_i87
#ISCELL
  standard offpage *
  page16_i88
#ISCELL
  standard offpage *
  page16_i89
#ISCELL
  standard offpage *
  page16_i90
#ISCELL
  standard offpage *
  page16_i91
#ISCELL
  standard offpage *
  page16_i92
#CELL
  pure_quanta q_cap *
  page16_i93
#ISCELL
  standard offpage *
  page16_i94
#ISCELL
  standard offpage *
  page16_i95
#ISCELL
  logical_power universal_gnd *
  page16_i96
#ISCELL
  logical_power universal_power *
  page16_i98
#CELL
  pure_quanta q_inductor *
  page16_i99
